# T6G (Grand Teton) — schematic netlist excerpt (pin names and nets, part order shuffled) for the footprints in the layout excerpt that follows; sources: Cadence DE-HDL packaged netlist, KiCad conversion of 04192023_DAF0TMB3IC0_F0TG_MB_C_brd_V02_OCP.brd

R1580  Q_RES  49.9 1% CHIP  pkg 0402LF  page 98 : A = I3C_SPD_DDRAF_CPU1_SCL ; B = I3C_SPD_DDRA_CPU1_SCL
PC223  Q_CAPP  470UF 2.5V 20% SPCAP  pkg SMLF  page 208 : A = PVDD11_S3_P0 ; B = GND

(kicad_pcb
	(version 20260206)
	(generator "pcbnew")
	(generator_version "10.0")
	(general
		(thickness 1.6)
		(legacy_teardrops no)
	)
	(paper "A4")
	(title_block
		(title "04192023_DAF0TMB3IC0_F0TG_MB_C_brd_V02_OCP.brd")
		(comment 1 "Grand Teton / footprints 7717-7718 of 8354")
	)
	(layers
		(0 "F.Cu" signal "TOP")
		(4 "In1.Cu" signal "GND")
		(6 "In2.Cu" signal "IN1")
		(8 "In3.Cu" signal "GND1")
		(10 "In4.Cu" signal "IN2")
		(12 "In5.Cu" signal "GND2")
		(14 "In6.Cu" signal "IN3")
		(16 "In7.Cu" signal "GND3")
		(18 "In8.Cu" signal "VCC")
		(20 "In9.Cu" signal "VCC1")
		(22 "In10.Cu" signal "GND4")
		(24 "In11.Cu" signal "IN4")
		(26 "In12.Cu" signal "GND5")
		(28 "In13.Cu" signal "IN5")
		(30 "In14.Cu" signal "GND6")
		(32 "In15.Cu" signal "IN6")
		(34 "In16.Cu" signal "GND7")
		(2 "B.Cu" signal "BOTTOM")
		(9 "F.Adhes" user "F.Adhesive")
		(11 "B.Adhes" user "B.Adhesive")
		(13 "F.Paste" user "Package Geometry/Pastemask Top")
		(15 "B.Paste" user "Package Geometry/Pastemask Bottom")
		(5 "F.SilkS" user "Ref Des/Silkscreen Top")
		(7 "B.SilkS" user "Ref Des/Silkscreen Bottom")
		(1 "F.Mask" user "Board Geometry/Soldermask Top")
		(3 "B.Mask" user "Board Geometry/Soldermask Bottom")
		(17 "Dwgs.User" user "User.Drawings")
		(19 "Cmts.User" user "User.Comments")
		(21 "Eco1.User" user "User.Eco1")
		(23 "Eco2.User" user "User.Eco2")
		(25 "Edge.Cuts" user "Board Geometry/Outline")
		(27 "Margin" user)
		(31 "F.CrtYd" user "Package Geometry/Place Bound Top")
		(29 "B.CrtYd" user "Package Geometry/Place Bound Bottom")
		(35 "F.Fab" user "Ref Des/Assembly Top")
		(33 "B.Fab" user "Ref Des/Assembly Bottom")
	)
	(footprint ""
		(layer "B.Cu")
		(at 59.401202 -195.012564 180)
		(property "Reference" "R1580"
			(at 0 0 0)
			(layer "B.SilkS")
			(hide yes)
			(effects
				(font
					(size 1.27 1.27)
				)
				(justify mirror)
			)
		)
		(property "Value" ""
			(at 0 0 0)
			(layer "B.Fab")
			(effects
				(font
					(size 1.27 1.27)
				)
				(justify mirror)
			)
		)
		(duplicate_pad_numbers_are_jumpers no)
		(fp_line
			(start 0.7874 0.4064)
			(end 0.7874 -0.4064)
			(stroke
				(width 0.1524)
				(type default)
			)
			(layer "B.SilkS")
		)
		(fp_line
			(start 0.7874 -0.4064)
			(end -0.7874 -0.4064)
			(stroke
				(width 0.1524)
				(type default)
			)
			(layer "B.SilkS")
		)
		(fp_line
			(start -0.7874 0.4064)
			(end 0.7874 0.4064)
			(stroke
				(width 0.1524)
				(type default)
			)
			(layer "B.SilkS")
		)
		(fp_line
			(start -0.7874 -0.4064)
			(end -0.7874 0.4064)
			(stroke
				(width 0.1524)
				(type default)
			)
			(layer "B.SilkS")
		)
		(fp_line
			(start 0.67945 0.3048)
			(end 0.67945 -0.305054)
			(stroke
				(width 0.1)
				(type default)
			)
			(layer "B.Fab")
		)
		(fp_line
			(start 0.67945 -0.305054)
			(end 0.12065 -0.305054)
			(stroke
				(width 0.1)
				(type default)
			)
			(layer "B.Fab")
		)
		(fp_line
			(start 0.12065 0.3048)
			(end 0.67945 0.3048)
			(stroke
				(width 0.1)
				(type default)
			)
			(layer "B.Fab")
		)
		(fp_line
			(start 0.12065 0.2794)
			(end 0.12065 0.3048)
			(stroke
				(width 0.1)
				(type default)
			)
			(layer "B.Fab")
		)
		(fp_line
			(start 0.12065 -0.2794)
			(end -0.12065 -0.2794)
			(stroke
				(width 0.1)
				(type default)
			)
			(layer "B.Fab")
		)
		(fp_line
			(start 0.12065 -0.305054)
			(end 0.12065 -0.2794)
			(stroke
				(width 0.1)
				(type default)
			)
			(layer "B.Fab")
		)
		(fp_line
			(start -0.120396 0.3048)
			(end -0.120396 0.2794)
			(stroke
				(width 0.1)
				(type default)
			)
			(layer "B.Fab")
		)
		(fp_line
			(start -0.120396 0.2794)
			(end 0.12065 0.2794)
			(stroke
				(width 0.1)
				(type default)
			)
			(layer "B.Fab")
		)
		(fp_line
			(start -0.12065 -0.2794)
			(end -0.12065 -0.3048)
			(stroke
				(width 0.1)
				(type default)
			)
			(layer "B.Fab")
		)
		(fp_line
			(start -0.12065 -0.3048)
			(end -0.67945 -0.3048)
			(stroke
				(width 0.1)
				(type default)
			)
			(layer "B.Fab")
		)
		(fp_line
			(start -0.67945 0.3048)
			(end -0.120396 0.3048)
			(stroke
				(width 0.1)
				(type default)
			)
			(layer "B.Fab")
		)
		(fp_line
			(start -0.67945 -0.3048)
			(end -0.67945 0.3048)
			(stroke
				(width 0.1)
				(type default)
			)
			(layer "B.Fab")
		)
		(pad "1" smd circle
			(at 0.40005 0)
			(size 0 0)
			(layers "B.Cu" "B.Mask" "B.Paste")
			(net "I3C_SPD_DDRAF_CPU1_SCL")
		)
		(pad "2" smd circle
			(at -0.40005 0)
			(size 0 0)
			(layers "B.Cu" "B.Mask" "B.Paste")
			(net "I3C_SPD_DDRA_CPU1_SCL")
		)
	)
	(footprint ""
		(layer "B.Cu")
		(at 423.668698 -343.961212 -90)
		(property "Reference" "PC223"
			(at 7.654036 -3.431286 270)
			(unlocked yes)
			(layer "B.SilkS")
			(effects
				(font
					(size 0.7874 0.5842)
					(thickness 0.1524)
				)
				(justify left mirror)
			)
		)
		(property "Value" ""
			(at 0 0 90)
			(layer "B.Fab")
			(effects
				(font
					(size 1.27 1.27)
				)
				(justify mirror)
			)
		)
		(duplicate_pad_numbers_are_jumpers no)
		(fp_line
			(start -4.533392 2.249932)
			(end 4.533392 2.249932)
			(stroke
				(width 0.1524)
				(type default)
			)
			(layer "B.SilkS")
		)
		(fp_line
			(start 4.533392 2.249932)
			(end 4.533392 -2.249932)
			(stroke
				(width 0.1524)
				(type default)
			)
			(layer "B.SilkS")
		)
		(fp_line
			(start -4.533392 -2.249932)
			(end -4.533392 2.249932)
			(stroke
				(width 0.1524)
				(type default)
			)
			(layer "B.SilkS")
		)
		(fp_line
			(start 4.533392 -2.249932)
			(end -4.533392 -2.249932)
			(stroke
				(width 0.1524)
				(type default)
			)
			(layer "B.SilkS")
		)
		(fp_rect
			(start 5.39242 2.326132)
			(end 4.533392 -2.326132)
			(stroke
				(width 0)
				(type default)
			)
			(fill yes)
			(layer "B.SilkS")
		)
		(fp_line
			(start -3.750056 2.249932)
			(end 3.750056 2.249932)
			(stroke
				(width 0.1)
				(type default)
			)
			(layer "B.Fab")
		)
		(fp_line
			(start 3.750056 2.249932)
			(end 3.750056 -2.249932)
			(stroke
				(width 0.1)
				(type default)
			)
			(layer "B.Fab")
		)
		(fp_line
			(start -3.750056 -2.249932)
			(end -3.750056 2.249932)
			(stroke
				(width 0.1)
				(type default)
			)
			(layer "B.Fab")
		)
		(fp_line
			(start 3.750056 -2.249932)
			(end -3.750056 -2.249932)
			(stroke
				(width 0.1)
				(type default)
			)
			(layer "B.Fab")
		)
		(fp_text user "+"
			(at 6.322314 0.786384 180)
			(unlocked yes)
			(layer "B.SilkS")
			(effects
				(font
					(size 1.905 1.4224)
					(thickness 0.1524)
				)
				(justify left mirror)
			)
		)
		(fp_text user "-"
			(at -4.8514 -0.14605 270)
			(unlocked yes)
			(layer "B.SilkS")
			(effects
				(font
					(size 1.905 1.4224)
					(thickness 0.1524)
				)
				(justify left mirror)
			)
		)
		(fp_text user "+"
			(at 6.322314 0.786384 180)
			(unlocked yes)
			(layer "B.Fab")
			(effects
				(font
					(size 1.905 1.4224)
					(thickness 0.1524)
				)
				(justify left mirror)
			)
		)
		(fp_text user "-"
			(at -4.8514 -0.14605 270)
			(unlocked yes)
			(layer "B.Fab")
			(effects
				(font
					(size 1.905 1.4224)
					(thickness 0.1524)
				)
				(justify left mirror)
			)
		)
		(pad "1" smd rect
			(at 3.199892 0 90)
			(size 2.413 2.8194)
			(layers "B.Cu" "B.Mask" "B.Paste")
			(net "PVDD11_S3_P0")
		)
		(pad "2" smd rect
			(at -3.199892 0 90)
			(size 2.413 2.8194)
			(layers "B.Cu" "B.Mask" "B.Paste")
			(net "GND")
		)
	)
)
